# BASEBOARD_FAB2 (Tioga Pass) — schematic netlist excerpt (pin names and nets, part order shuffled) for the footprints in the layout excerpt that follows; sources: Cadence DE-HDL packaged netlist, KiCad conversion of Wiwynn_Tioga_Pass_MB.brd

R2P20  RES  100.0 1% CHIP  pkg 0402  page 196 : A = PWRGD_P5V_R ; B = PWRGD_P5V
C3P25  CAP  0.22UF 16V 10% X7R  pkg 0402  page 107 : A = P3E_CPU0_PE1_SS_TXN<3> ; B = P3E_CPU0_PE1_PCH_TXN<3>
R1W37  RES  4.75K 1% CHIP  pkg 0402  page 176 : A = P3V3_STBY ; B = SMB_DEBUG_STBY_LVC3_SDA_CONN

(kicad_pcb
	(version 20260206)
	(generator "pcbnew")
	(generator_version "10.0")
	(general
		(thickness 1.6)
		(legacy_teardrops no)
	)
	(paper "A4")
	(title_block
		(title "Wiwynn_Tioga_Pass_MB.brd")
		(comment 1 "Tioga Pass / footprints 3947-3949 of 4770")
	)
	(layers
		(0 "F.Cu" signal "TOP")
		(4 "In1.Cu" signal "L2GND")
		(6 "In2.Cu" signal "L3")
		(8 "In3.Cu" signal "L4GND")
		(10 "In4.Cu" signal "L5")
		(12 "In5.Cu" signal "L6GND")
		(14 "In6.Cu" signal "L7VCC")
		(16 "In7.Cu" signal "L8VCC")
		(18 "In8.Cu" signal "L9GND")
		(20 "In9.Cu" signal "L10")
		(22 "In10.Cu" signal "L11GND")
		(24 "In11.Cu" signal "L12")
		(26 "In12.Cu" signal "L13GND")
		(2 "B.Cu" signal "BOTTOM")
		(9 "F.Adhes" user "F.Adhesive")
		(11 "B.Adhes" user "B.Adhesive")
		(13 "F.Paste" user "Package Geometry/Pastemask Top")
		(15 "B.Paste" user "Package Geometry/Pastemask Bottom")
		(5 "F.SilkS" user "Ref Des/Silkscreen Top")
		(7 "B.SilkS" user "Ref Des/Silkscreen Bottom")
		(1 "F.Mask" user "Board Geometry/Soldermask Top")
		(3 "B.Mask" user "Board Geometry/Soldermask Bottom")
		(17 "Dwgs.User" user "User.Drawings")
		(19 "Cmts.User" user "User.Comments")
		(21 "Eco1.User" user "User.Eco1")
		(23 "Eco2.User" user "User.Eco2")
		(25 "Edge.Cuts" user "Board Geometry/Outline")
		(27 "Margin" user)
		(31 "F.CrtYd" user "Package Geometry/Place Bound Top")
		(29 "B.CrtYd" user "Package Geometry/Place Bound Bottom")
		(35 "F.Fab" user "Ref Des/Assembly Top")
		(33 "B.Fab" user "Ref Des/Assembly Bottom")
	)
	(footprint ""
		(layer "B.Cu")
		(at 476.414084 -135.41756 -90)
		(property "Reference" "R1W37"
			(at 0.8382 -0.67818 270)
			(unlocked yes)
			(layer "B.SilkS")
			(effects
				(font
					(size 0.4064 0.254)
					(thickness 0.1524)
				)
				(justify left mirror)
			)
		)
		(property "Value" ""
			(at 0 0 90)
			(layer "B.Fab")
			(effects
				(font
					(size 1.27 1.27)
				)
				(justify mirror)
			)
		)
		(duplicate_pad_numbers_are_jumpers no)
		(fp_poly
			(pts
				(xy 0.2794 -0.1016) (xy -0.2794 -0.1016) (xy -0.2794 0.9906) (xy 0.2794 0.9906)
			)
			(stroke
				(width 0)
				(type default)
			)
			(fill no)
			(layer "B.CrtYd")
		)
		(fp_line
			(start -0.2794 0.9906)
			(end -0.2794 -0.1016)
			(stroke
				(width 0.1)
				(type default)
			)
			(layer "B.Fab")
		)
		(fp_line
			(start 0.2794 0.9906)
			(end -0.2794 0.9906)
			(stroke
				(width 0.1)
				(type default)
			)
			(layer "B.Fab")
		)
		(fp_line
			(start -0.2794 -0.1016)
			(end 0.2794 -0.1016)
			(stroke
				(width 0.1)
				(type default)
			)
			(layer "B.Fab")
		)
		(fp_line
			(start 0.2794 -0.1016)
			(end 0.2794 0.9906)
			(stroke
				(width 0.1)
				(type default)
			)
			(layer "B.Fab")
		)
		(pad "1" smd rect
			(at 0 0 90)
			(size 0.508 0.508)
			(layers "B.Cu" "B.Mask" "B.Paste")
			(net "P3V3_STBY")
		)
		(pad "2" smd rect
			(at 0 0.889 90)
			(size 0.508 0.508)
			(layers "B.Cu" "B.Mask" "B.Paste")
			(net "SMB_DEBUG_STBY_LVC3_SDA_CONN")
		)
		(zone
			(layer "B.Cu")
			(hatch none 0.5)
			(connect_pads
				(clearance 0)
			)
			(min_thickness 0.25)
			(keepout
				(tracks not_allowed)
				(vias allowed)
				(pads allowed)
				(copperpour not_allowed)
				(footprints allowed)
			)
			(placement
				(enabled no)
				(sheetname "")
			)
			(fill
				(thermal_gap 0.5)
				(thermal_bridge_width 0.5)
				(island_removal_mode 0)
			)
			(polygon
				(pts
					(xy 475.779084 -135.16356) (xy 475.779084 -135.67156) (xy 476.160084 -135.67156) (xy 476.160084 -135.16356)
				)
			)
		)
		(zone
			(layer "B.Cu")
			(hatch none 0.5)
			(connect_pads
				(clearance 0)
			)
			(min_thickness 0.25)
			(keepout
				(tracks allowed)
				(vias not_allowed)
				(pads allowed)
				(copperpour not_allowed)
				(footprints allowed)
			)
			(placement
				(enabled no)
				(sheetname "")
			)
			(fill
				(thermal_gap 0.5)
				(thermal_bridge_width 0.5)
				(island_removal_mode 0)
			)
			(polygon
				(pts
					(xy 476.160084 -135.16356) (xy 476.160084 -135.67156) (xy 475.779084 -135.67156) (xy 475.779084 -135.16356)
				)
			)
		)
	)
	(footprint ""
		(layer "B.Cu")
		(at 414.2105 -4.318 -90)
		(property "Reference" "R2P20"
			(at 0 0 90)
			(layer "B.SilkS")
			(hide yes)
			(effects
				(font
					(size 1.27 1.27)
				)
				(justify mirror)
			)
		)
		(property "Value" ""
			(at 0 0 90)
			(layer "B.Fab")
			(effects
				(font
					(size 1.27 1.27)
				)
				(justify mirror)
			)
		)
		(duplicate_pad_numbers_are_jumpers no)
		(fp_rect
			(start 0.2794 -0.1016)
			(end -0.2794 0.9906)
			(stroke
				(width 0)
				(type default)
			)
			(fill no)
			(layer "B.CrtYd")
		)
		(fp_line
			(start -0.2794 0.9906)
			(end -0.2794 -0.1016)
			(stroke
				(width 0.1)
				(type default)
			)
			(layer "B.Fab")
		)
		(fp_line
			(start 0.2794 0.9906)
			(end -0.2794 0.9906)
			(stroke
				(width 0.1)
				(type default)
			)
			(layer "B.Fab")
		)
		(fp_line
			(start -0.2794 -0.1016)
			(end 0.2794 -0.1016)
			(stroke
				(width 0.1)
				(type default)
			)
			(layer "B.Fab")
		)
		(fp_line
			(start 0.2794 -0.1016)
			(end 0.2794 0.9906)
			(stroke
				(width 0.1)
				(type default)
			)
			(layer "B.Fab")
		)
		(pad "1" smd rect
			(at 0 0 90)
			(size 0.508 0.508)
			(layers "B.Cu" "B.Mask" "B.Paste")
			(net "PWRGD_P5V_R")
		)
		(pad "2" smd rect
			(at 0 0.889 90)
			(size 0.508 0.508)
			(layers "B.Cu" "B.Mask" "B.Paste")
			(net "PWRGD_P5V")
		)
		(zone
			(layer "B.Cu")
			(hatch none 0.5)
			(connect_pads
				(clearance 0)
			)
			(min_thickness 0.25)
			(keepout
				(tracks allowed)
				(vias not_allowed)
				(pads allowed)
				(copperpour not_allowed)
				(footprints allowed)
			)
			(placement
				(enabled no)
				(sheetname "")
			)
			(fill
				(thermal_gap 0.5)
				(thermal_bridge_width 0.5)
				(island_removal_mode 0)
			)
			(polygon
				(pts
					(xy 413.9565 -4.064) (xy 413.9565 -4.572) (xy 413.5755 -4.572) (xy 413.5755 -4.064)
				)
			)
		)
		(zone
			(layer "B.Cu")
			(hatch none 0.5)
			(connect_pads
				(clearance 0)
			)
			(min_thickness 0.25)
			(keepout
				(tracks not_allowed)
				(vias allowed)
				(pads allowed)
				(copperpour not_allowed)
				(footprints allowed)
			)
			(placement
				(enabled no)
				(sheetname "")
			)
			(fill
				(thermal_gap 0.5)
				(thermal_bridge_width 0.5)
				(island_removal_mode 0)
			)
			(polygon
				(pts
					(xy 413.9565 -4.064) (xy 413.9565 -4.572) (xy 413.5755 -4.572) (xy 413.5755 -4.064)
				)
			)
		)
	)
	(footprint ""
		(layer "B.Cu")
		(at 348.57436 -77.788516 180)
		(property "Reference" "C3P25"
			(at 0 0 0)
			(layer "B.SilkS")
			(hide yes)
			(effects
				(font
					(size 1.27 1.27)
				)
				(justify mirror)
			)
		)
		(property "Value" ""
			(at 0 0 0)
			(layer "B.Fab")
			(effects
				(font
					(size 1.27 1.27)
				)
				(justify mirror)
			)
		)
		(duplicate_pad_numbers_are_jumpers no)
		(fp_poly
			(pts
				(xy -0.3048 -0.1016) (xy -0.3048 0.9906) (xy 0.3048 0.9906) (xy 0.3048 -0.1016)
			)
			(stroke
				(width 0)
				(type default)
			)
			(fill no)
			(layer "B.CrtYd")
		)
		(fp_line
			(start 0.3048 0.9906)
			(end -0.3048 0.9906)
			(stroke
				(width 0.1)
				(type default)
			)
			(layer "B.Fab")
		)
		(fp_line
			(start 0.3048 -0.1016)
			(end 0.3048 0.9906)
			(stroke
				(width 0.1)
				(type default)
			)
			(layer "B.Fab")
		)
		(fp_line
			(start -0.3048 0.9906)
			(end -0.3048 -0.1016)
			(stroke
				(width 0.1)
				(type default)
			)
			(layer "B.Fab")
		)
		(fp_line
			(start -0.3048 -0.1016)
			(end 0.3048 -0.1016)
			(stroke
				(width 0.1)
				(type default)
			)
			(layer "B.Fab")
		)
		(pad "1" smd rect
			(at 0 0)
			(size 0.508 0.508)
			(layers "B.Cu" "B.Mask" "B.Paste")
			(net "P3E_CPU0_PE1_SS_TXN<3>")
		)
		(pad "2" smd rect
			(at 0 0.889)
			(size 0.508 0.508)
			(layers "B.Cu" "B.Mask" "B.Paste")
			(net "P3E_CPU0_PE1_PCH_TXN<3>")
		)
		(zone
			(layer "B.Cu")
			(hatch none 0.5)
			(connect_pads
				(clearance 0)
			)
			(min_thickness 0.25)
			(keepout
				(tracks not_allowed)
				(vias allowed)
				(pads allowed)
				(copperpour not_allowed)
				(footprints allowed)
			)
			(placement
				(enabled no)
				(sheetname "")
			)
			(fill
				(thermal_gap 0.5)
				(thermal_bridge_width 0.5)
				(island_removal_mode 0)
			)
			(polygon
				(pts
					(xy 348.32036 -78.423516) (xy 348.82836 -78.423516) (xy 348.82836 -78.042516) (xy 348.32036 -78.042516)
				)
			)
		)
		(zone
			(layer "B.Cu")
			(hatch none 0.5)
			(connect_pads
				(clearance 0)
			)
			(min_thickness 0.25)
			(keepout
				(tracks allowed)
				(vias not_allowed)
				(pads allowed)
				(copperpour not_allowed)
				(footprints allowed)
			)
			(placement
				(enabled no)
				(sheetname "")
			)
			(fill
				(thermal_gap 0.5)
				(thermal_bridge_width 0.5)
				(island_removal_mode 0)
			)
			(polygon
				(pts
					(xy 348.32036 -78.042516) (xy 348.82836 -78.042516) (xy 348.82836 -78.423516) (xy 348.32036 -78.423516)
				)
			)
		)
	)
)
